# BASEBOARD_FAB2 (Tioga Pass) — schematic netlist excerpt (pin names and nets, part order shuffled) for the footprints in the layout excerpt that follows; sources: Cadence DE-HDL packaged netlist, KiCad conversion of Wiwynn_Tioga_Pass_MB.brd

C2R6  CAP  470PF 50V 10% EMPTY  pkg 0402LF  page 181 : A = FM_PS_EN ; B = GND
R9F69  RES  0.0 5% CHIP  pkg 0402  page 158 : A = SP2_BMC_CM_UART_RX_R ; B = SP2_BMC_CM_UART_RX_R1
R6D14  RES  240 1.0% EMPTY  pkg 0402  page 90 : A = GND ; B = PD_CPU0_EAR_N

(kicad_pcb
	(version 20260206)
	(generator "pcbnew")
	(generator_version "10.0")
	(general
		(thickness 1.6)
		(legacy_teardrops no)
	)
	(paper "A4")
	(title_block
		(title "Wiwynn_Tioga_Pass_MB.brd")
		(comment 1 "Tioga Pass / footprints 2159-2161 of 4770")
	)
	(layers
		(0 "F.Cu" signal "TOP")
		(4 "In1.Cu" signal "L2GND")
		(6 "In2.Cu" signal "L3")
		(8 "In3.Cu" signal "L4GND")
		(10 "In4.Cu" signal "L5")
		(12 "In5.Cu" signal "L6GND")
		(14 "In6.Cu" signal "L7VCC")
		(16 "In7.Cu" signal "L8VCC")
		(18 "In8.Cu" signal "L9GND")
		(20 "In9.Cu" signal "L10")
		(22 "In10.Cu" signal "L11GND")
		(24 "In11.Cu" signal "L12")
		(26 "In12.Cu" signal "L13GND")
		(2 "B.Cu" signal "BOTTOM")
		(9 "F.Adhes" user "F.Adhesive")
		(11 "B.Adhes" user "B.Adhesive")
		(13 "F.Paste" user "Package Geometry/Pastemask Top")
		(15 "B.Paste" user "Package Geometry/Pastemask Bottom")
		(5 "F.SilkS" user "Ref Des/Silkscreen Top")
		(7 "B.SilkS" user "Ref Des/Silkscreen Bottom")
		(1 "F.Mask" user "Board Geometry/Soldermask Top")
		(3 "B.Mask" user "Board Geometry/Soldermask Bottom")
		(17 "Dwgs.User" user "User.Drawings")
		(19 "Cmts.User" user "User.Comments")
		(21 "Eco1.User" user "User.Eco1")
		(23 "Eco2.User" user "User.Eco2")
		(25 "Edge.Cuts" user "Board Geometry/Outline")
		(27 "Margin" user)
		(31 "F.CrtYd" user "Package Geometry/Place Bound Top")
		(29 "B.CrtYd" user "Package Geometry/Place Bound Bottom")
		(35 "F.Fab" user "Ref Des/Assembly Top")
		(33 "B.Fab" user "Ref Des/Assembly Bottom")
	)
	(footprint ""
		(layer "F.Cu")
		(at 278.070056 -69.969888)
		(property "Reference" "R6D14"
			(at 0 0 0)
			(layer "F.SilkS")
			(hide yes)
			(effects
				(font
					(size 1.27 1.27)
				)
			)
		)
		(property "Value" ""
			(at 0 0 0)
			(layer "F.Fab")
			(effects
				(font
					(size 1.27 1.27)
				)
			)
		)
		(duplicate_pad_numbers_are_jumpers no)
		(fp_poly
			(pts
				(xy -0.2794 -0.1016) (xy 0.2794 -0.1016) (xy 0.2794 0.9906) (xy -0.2794 0.9906)
			)
			(stroke
				(width 0)
				(type default)
			)
			(fill no)
			(layer "F.CrtYd")
		)
		(fp_line
			(start -0.2794 -0.1016)
			(end -0.2794 0.9906)
			(stroke
				(width 0.1)
				(type default)
			)
			(layer "F.Fab")
		)
		(fp_line
			(start -0.2794 0.9906)
			(end 0.2794 0.9906)
			(stroke
				(width 0.1)
				(type default)
			)
			(layer "F.Fab")
		)
		(fp_line
			(start 0.2794 -0.1016)
			(end -0.2794 -0.1016)
			(stroke
				(width 0.1)
				(type default)
			)
			(layer "F.Fab")
		)
		(fp_line
			(start 0.2794 0.9906)
			(end 0.2794 -0.1016)
			(stroke
				(width 0.1)
				(type default)
			)
			(layer "F.Fab")
		)
		(pad "1" smd rect
			(at 0 0)
			(size 0.508 0.508)
			(layers "F.Cu" "F.Mask" "F.Paste")
			(net "GND")
		)
		(pad "2" smd rect
			(at 0 0.889)
			(size 0.508 0.508)
			(layers "F.Cu" "F.Mask" "F.Paste")
			(net "PD_CPU0_EAR_N")
		)
		(zone
			(layer "F.Cu")
			(hatch none 0.5)
			(connect_pads
				(clearance 0)
			)
			(min_thickness 0.25)
			(keepout
				(tracks allowed)
				(vias not_allowed)
				(pads allowed)
				(copperpour not_allowed)
				(footprints allowed)
			)
			(placement
				(enabled no)
				(sheetname "")
			)
			(fill
				(thermal_gap 0.5)
				(thermal_bridge_width 0.5)
				(island_removal_mode 0)
			)
			(polygon
				(pts
					(xy 277.816056 -69.715888) (xy 278.324056 -69.715888) (xy 278.324056 -69.334888) (xy 277.816056 -69.334888)
				)
			)
		)
		(zone
			(layer "F.Cu")
			(hatch none 0.5)
			(connect_pads
				(clearance 0)
			)
			(min_thickness 0.25)
			(keepout
				(tracks not_allowed)
				(vias allowed)
				(pads allowed)
				(copperpour not_allowed)
				(footprints allowed)
			)
			(placement
				(enabled no)
				(sheetname "")
			)
			(fill
				(thermal_gap 0.5)
				(thermal_bridge_width 0.5)
				(island_removal_mode 0)
			)
			(polygon
				(pts
					(xy 277.816056 -69.334888) (xy 278.324056 -69.334888) (xy 278.324056 -69.715888) (xy 277.816056 -69.715888)
				)
			)
		)
	)
	(footprint ""
		(layer "F.Cu")
		(at 411.48 -87.8205 180)
		(property "Reference" "C2R6"
			(at 0 0 180)
			(layer "F.SilkS")
			(hide yes)
			(effects
				(font
					(size 1.27 1.27)
				)
			)
		)
		(property "Value" ""
			(at 0 0 180)
			(layer "F.Fab")
			(effects
				(font
					(size 1.27 1.27)
				)
			)
		)
		(duplicate_pad_numbers_are_jumpers no)
		(fp_poly
			(pts
				(xy 0.3048 -0.1016) (xy 0.3048 0.9906) (xy -0.3048 0.9906) (xy -0.3048 -0.1016)
			)
			(stroke
				(width 0)
				(type default)
			)
			(fill no)
			(layer "F.CrtYd")
		)
		(fp_line
			(start 0.3048 0.9906)
			(end 0.3048 -0.1016)
			(stroke
				(width 0.1)
				(type default)
			)
			(layer "F.Fab")
		)
		(fp_line
			(start 0.3048 -0.1016)
			(end -0.3048 -0.1016)
			(stroke
				(width 0.1)
				(type default)
			)
			(layer "F.Fab")
		)
		(fp_line
			(start -0.3048 0.9906)
			(end 0.3048 0.9906)
			(stroke
				(width 0.1)
				(type default)
			)
			(layer "F.Fab")
		)
		(fp_line
			(start -0.3048 -0.1016)
			(end -0.3048 0.9906)
			(stroke
				(width 0.1)
				(type default)
			)
			(layer "F.Fab")
		)
		(pad "1" smd rect
			(at 0 0 180)
			(size 0.508 0.508)
			(layers "F.Cu" "F.Mask" "F.Paste")
			(net "FM_PS_EN")
		)
		(pad "2" smd rect
			(at 0 0.889 180)
			(size 0.508 0.508)
			(layers "F.Cu" "F.Mask" "F.Paste")
			(net "GND")
		)
		(zone
			(layer "F.Cu")
			(hatch none 0.5)
			(connect_pads
				(clearance 0)
			)
			(min_thickness 0.25)
			(keepout
				(tracks not_allowed)
				(vias allowed)
				(pads allowed)
				(copperpour not_allowed)
				(footprints allowed)
			)
			(placement
				(enabled no)
				(sheetname "")
			)
			(fill
				(thermal_gap 0.5)
				(thermal_bridge_width 0.5)
				(island_removal_mode 0)
			)
			(polygon
				(pts
					(xy 411.734 -88.4555) (xy 411.226 -88.4555) (xy 411.226 -88.0745) (xy 411.734 -88.0745)
				)
			)
		)
		(zone
			(layer "F.Cu")
			(hatch none 0.5)
			(connect_pads
				(clearance 0)
			)
			(min_thickness 0.25)
			(keepout
				(tracks allowed)
				(vias not_allowed)
				(pads allowed)
				(copperpour not_allowed)
				(footprints allowed)
			)
			(placement
				(enabled no)
				(sheetname "")
			)
			(fill
				(thermal_gap 0.5)
				(thermal_bridge_width 0.5)
				(island_removal_mode 0)
			)
			(polygon
				(pts
					(xy 411.734 -88.0745) (xy 411.226 -88.0745) (xy 411.226 -88.4555) (xy 411.734 -88.4555)
				)
			)
		)
	)
	(footprint ""
		(layer "F.Cu")
		(at 486.687876 -27.227784 180)
		(property "Reference" "R9F69"
			(at 0 0 180)
			(layer "F.SilkS")
			(hide yes)
			(effects
				(font
					(size 1.27 1.27)
				)
			)
		)
		(property "Value" ""
			(at 0 0 180)
			(layer "F.Fab")
			(effects
				(font
					(size 1.27 1.27)
				)
			)
		)
		(duplicate_pad_numbers_are_jumpers no)
		(fp_poly
			(pts
				(xy -0.2794 -0.1016) (xy 0.2794 -0.1016) (xy 0.2794 0.9906) (xy -0.2794 0.9906)
			)
			(stroke
				(width 0)
				(type default)
			)
			(fill no)
			(layer "F.CrtYd")
		)
		(fp_line
			(start 0.2794 0.9906)
			(end 0.2794 -0.1016)
			(stroke
				(width 0.1)
				(type default)
			)
			(layer "F.Fab")
		)
		(fp_line
			(start 0.2794 -0.1016)
			(end -0.2794 -0.1016)
			(stroke
				(width 0.1)
				(type default)
			)
			(layer "F.Fab")
		)
		(fp_line
			(start -0.2794 0.9906)
			(end 0.2794 0.9906)
			(stroke
				(width 0.1)
				(type default)
			)
			(layer "F.Fab")
		)
		(fp_line
			(start -0.2794 -0.1016)
			(end -0.2794 0.9906)
			(stroke
				(width 0.1)
				(type default)
			)
			(layer "F.Fab")
		)
		(pad "1" smd rect
			(at 0 0 180)
			(size 0.508 0.508)
			(layers "F.Cu" "F.Mask" "F.Paste")
			(net "SP2_BMC_CM_UART_RX_R")
		)
		(pad "2" smd rect
			(at 0 0.889 180)
			(size 0.508 0.508)
			(layers "F.Cu" "F.Mask" "F.Paste")
			(net "SP2_BMC_CM_UART_RX_R1")
		)
		(zone
			(layer "F.Cu")
			(hatch none 0.5)
			(connect_pads
				(clearance 0)
			)
			(min_thickness 0.25)
			(keepout
				(tracks not_allowed)
				(vias allowed)
				(pads allowed)
				(copperpour not_allowed)
				(footprints allowed)
			)
			(placement
				(enabled no)
				(sheetname "")
			)
			(fill
				(thermal_gap 0.5)
				(thermal_bridge_width 0.5)
				(island_removal_mode 0)
			)
			(polygon
				(pts
					(xy 486.941876 -27.862784) (xy 486.433876 -27.862784) (xy 486.433876 -27.481784) (xy 486.941876 -27.481784)
				)
			)
		)
		(zone
			(layer "F.Cu")
			(hatch none 0.5)
			(connect_pads
				(clearance 0)
			)
			(min_thickness 0.25)
			(keepout
				(tracks allowed)
				(vias not_allowed)
				(pads allowed)
				(copperpour not_allowed)
				(footprints allowed)
			)
			(placement
				(enabled no)
				(sheetname "")
			)
			(fill
				(thermal_gap 0.5)
				(thermal_bridge_width 0.5)
				(island_removal_mode 0)
			)
			(polygon
				(pts
					(xy 486.941876 -27.481784) (xy 486.433876 -27.481784) (xy 486.433876 -27.862784) (xy 486.941876 -27.862784)
				)
			)
		)
	)
)
